(kicad_pcb
	(version 20240108)
	(generator "pcbnew")
	(generator_version "8.0")
	(general
		(thickness 1.586)
		(legacy_teardrops no)
	)
	(paper "A4")
	(title_block
		(title "GMSL Serializer")
		(date "2024-11-27")
		(rev "1.1.1")
		(company "Antmicro Ltd")
		(comment 1 "www.antmicro.com")
		(comment 9 "footprints 114-117 of 117")
	)
	(layers
		(0 "F.Cu" signal)
		(1 "In1.Cu" power)
		(2 "In2.Cu" power)
		(31 "B.Cu" signal)
		(32 "B.Adhes" user "B.Adhesive")
		(33 "F.Adhes" user "F.Adhesive")
		(34 "B.Paste" user)
		(35 "F.Paste" user)
		(36 "B.SilkS" user "B.Silkscreen")
		(37 "F.SilkS" user "F.Silkscreen")
		(38 "B.Mask" user)
		(39 "F.Mask" user)
		(40 "Dwgs.User" user "User.Drawings")
		(41 "Cmts.User" user "User.Comments")
		(42 "Eco1.User" user "User.Eco1")
		(43 "Eco2.User" user "User.Eco2")
		(44 "Edge.Cuts" user)
		(45 "Margin" user)
		(46 "B.CrtYd" user "B.Courtyard")
		(47 "F.CrtYd" user "F.Courtyard")
		(48 "B.Fab" user)
		(49 "F.Fab" user)
	)
	(footprint "antmicro-footprints:C_0402_1005Metric"
		(layer "B.Cu")
		(at 150.86 102.13 45)
		(descr "Capacitor SMD 0402")
		(tags "capacitor SMD 0402")
		(property "Reference" "C25"
			(at -3.563818 0.367696 45)
			(layer "B.SilkS")
			(effects
				(font
					(size 0.7 0.7)
					(thickness 0.15)
				)
				(justify right bottom mirror)
			)
		)
		(property "Value" "C_10u_0402"
			(at -0.676445 -2.119857 45)
			(layer "B.Fab")
			(effects
				(font
					(size 0.7 0.7)
					(thickness 0.15)
				)
				(justify right bottom mirror)
			)
		)
		(property "Footprint" "antmicro-footprints:C_0402_1005Metric"
			(at 0 0 45)
			(layer "F.Fab")
			(hide yes)
			(effects
				(font
					(size 1.27 1.27)
					(thickness 0.15)
				)
			)
		)
		(property "Datasheet" "https://www.yageo.com/en/Chart/Download/pdf/CC0402MRX5R5BB106"
			(at 0 0 45)
			(layer "F.Fab")
			(hide yes)
			(effects
				(font
					(size 1.27 1.27)
					(thickness 0.15)
				)
			)
		)
		(property "Author" "Antmicro"
			(at 116.402687 -76.760944 0)
			(layer "B.Fab")
			(hide yes)
			(effects
				(font
					(size 1 1)
					(thickness 0.15)
				)
				(justify mirror)
			)
		)
		(property "Dielectric" ""
			(at 116.402687 -76.760944 0)
			(layer "B.Fab")
			(hide yes)
			(effects
				(font
					(size 1 1)
					(thickness 0.15)
				)
				(justify mirror)
			)
		)
		(property "License" "Apache-2.0"
			(at 116.402687 -76.760944 0)
			(layer "B.Fab")
			(hide yes)
			(effects
				(font
					(size 1 1)
					(thickness 0.15)
				)
				(justify mirror)
			)
		)
		(property "MPN" "CC0402MRX5R5BB106"
			(at 116.402687 -76.760944 0)
			(layer "B.Fab")
			(hide yes)
			(effects
				(font
					(size 1 1)
					(thickness 0.15)
				)
				(justify mirror)
			)
		)
		(property "Manufacturer" "YAGEO"
			(at 116.402687 -76.760944 0)
			(layer "B.Fab")
			(hide yes)
			(effects
				(font
					(size 1 1)
					(thickness 0.15)
				)
				(justify mirror)
			)
		)
		(property "Val" "10u"
			(at 116.402687 -76.760944 0)
			(layer "B.Fab")
			(hide yes)
			(effects
				(font
					(size 1 1)
					(thickness 0.15)
				)
				(justify mirror)
			)
		)
		(property "Voltage" ""
			(at 116.402687 -76.760944 0)
			(layer "B.Fab")
			(hide yes)
			(effects
				(font
					(size 1 1)
					(thickness 0.15)
				)
				(justify mirror)
			)
		)
		(sheetname "Serializer")
		(sheetfile "serializer.kicad_sch")
		(attr smd)
		(fp_poly
			(pts
				(xy -0.925 0.47) (xy 0.925 0.47) (xy 0.925 -0.47) (xy -0.925 -0.47)
			)
			(stroke
				(width 0.05)
				(type default)
			)
			(fill none)
			(layer "B.CrtYd")
		)
		(fp_line
			(start -0.494 -0.248)
			(end 0.504 -0.248)
			(stroke
				(width 0.15)
				(type solid)
			)
			(layer "B.Fab")
		)
		(fp_line
			(start -0.494 0.25)
			(end -0.494 -0.248)
			(stroke
				(width 0.15)
				(type solid)
			)
			(layer "B.Fab")
		)
		(fp_line
			(start 0.504 -0.248)
			(end 0.504 0.25)
			(stroke
				(width 0.15)
				(type solid)
			)
			(layer "B.Fab")
		)
		(fp_line
			(start 0.504 0.25)
			(end -0.494 0.25)
			(stroke
				(width 0.15)
				(type solid)
			)
			(layer "B.Fab")
		)
		(fp_text user "${REFERENCE}"
			(at -0.939 -4.599 45)
			(layer "B.Fab")
			(hide yes)
			(effects
				(font
					(size 0.7 0.7)
					(thickness 0.15)
				)
				(justify right bottom mirror)
			)
		)
		(fp_text user "Author: Antmicro"
			(at -0.939 -3.399 45)
			(layer "B.Fab")
			(hide yes)
			(effects
				(font
					(size 0.7 0.7)
					(thickness 0.15)
				)
				(justify right bottom mirror)
			)
		)
		(fp_text user "License: Apache-2.0"
			(at -0.939 -5.799 45)
			(layer "B.Fab")
			(hide yes)
			(effects
				(font
					(size 0.7 0.7)
					(thickness 0.15)
				)
				(justify right bottom mirror)
			)
		)
		(pad "1" smd roundrect
			(at -0.48 0 45)
			(size 0.59 0.64)
			(layers "B.Cu" "B.Paste" "B.Mask")
			(roundrect_rratio 0.25)
			(net 1 "GND")
			(pintype "passive")
		)
		(pad "2" smd roundrect
			(at 0.48 0 45)
			(size 0.59 0.64)
			(layers "B.Cu" "B.Paste" "B.Mask")
			(roundrect_rratio 0.25)
			(net 11 "+1V8")
			(pintype "passive")
		)
	)
	(footprint "antmicro-footprints:C_0402_1005Metric"
		(layer "B.Cu")
		(at 147.39 98.66 45)
		(descr "Capacitor SMD 0402")
		(tags "capacitor SMD 0402")
		(property "Reference" "C26"
			(at -3.592102 0.410122 45)
			(layer "B.SilkS")
			(effects
				(font
					(size 0.7 0.7)
					(thickness 0.15)
				)
				(justify right bottom mirror)
			)
		)
		(property "Value" "C_10u_0402"
			(at -1.022927 -2.155213 45)
			(layer "B.Fab")
			(effects
				(font
					(size 0.7 0.7)
					(thickness 0.15)
				)
				(justify right bottom mirror)
			)
		)
		(property "Footprint" "antmicro-footprints:C_0402_1005Metric"
			(at 0 0 45)
			(layer "F.Fab")
			(hide yes)
			(effects
				(font
					(size 1.27 1.27)
					(thickness 0.15)
				)
			)
		)
		(property "Datasheet" "https://www.yageo.com/en/Chart/Download/pdf/CC0402MRX5R5BB106"
			(at 0 0 45)
			(layer "F.Fab")
			(hide yes)
			(effects
				(font
					(size 1.27 1.27)
					(thickness 0.15)
				)
			)
		)
		(property "Author" "Antmicro"
			(at 112.932687 -75.323623 0)
			(layer "B.Fab")
			(hide yes)
			(effects
				(font
					(size 1 1)
					(thickness 0.15)
				)
				(justify mirror)
			)
		)
		(property "Dielectric" ""
			(at 112.932687 -75.323623 0)
			(layer "B.Fab")
			(hide yes)
			(effects
				(font
					(size 1 1)
					(thickness 0.15)
				)
				(justify mirror)
			)
		)
		(property "License" "Apache-2.0"
			(at 112.932687 -75.323623 0)
			(layer "B.Fab")
			(hide yes)
			(effects
				(font
					(size 1 1)
					(thickness 0.15)
				)
				(justify mirror)
			)
		)
		(property "MPN" "CC0402MRX5R5BB106"
			(at 112.932687 -75.323623 0)
			(layer "B.Fab")
			(hide yes)
			(effects
				(font
					(size 1 1)
					(thickness 0.15)
				)
				(justify mirror)
			)
		)
		(property "Manufacturer" "YAGEO"
			(at 112.932687 -75.323623 0)
			(layer "B.Fab")
			(hide yes)
			(effects
				(font
					(size 1 1)
					(thickness 0.15)
				)
				(justify mirror)
			)
		)
		(property "Val" "10u"
			(at 112.932687 -75.323623 0)
			(layer "B.Fab")
			(hide yes)
			(effects
				(font
					(size 1 1)
					(thickness 0.15)
				)
				(justify mirror)
			)
		)
		(property "Voltage" ""
			(at 112.932687 -75.323623 0)
			(layer "B.Fab")
			(hide yes)
			(effects
				(font
					(size 1 1)
					(thickness 0.15)
				)
				(justify mirror)
			)
		)
		(sheetname "Serializer")
		(sheetfile "serializer.kicad_sch")
		(attr smd)
		(fp_poly
			(pts
				(xy -0.925 0.47) (xy 0.925 0.47) (xy 0.925 -0.47) (xy -0.925 -0.47)
			)
			(stroke
				(width 0.05)
				(type default)
			)
			(fill none)
			(layer "B.CrtYd")
		)
		(fp_line
			(start -0.494 -0.248)
			(end 0.504 -0.248)
			(stroke
				(width 0.15)
				(type solid)
			)
			(layer "B.Fab")
		)
		(fp_line
			(start -0.494 0.25)
			(end -0.494 -0.248)
			(stroke
				(width 0.15)
				(type solid)
			)
			(layer "B.Fab")
		)
		(fp_line
			(start 0.504 -0.248)
			(end 0.504 0.25)
			(stroke
				(width 0.15)
				(type solid)
			)
			(layer "B.Fab")
		)
		(fp_line
			(start 0.504 0.25)
			(end -0.494 0.25)
			(stroke
				(width 0.15)
				(type solid)
			)
			(layer "B.Fab")
		)
		(fp_text user "${REFERENCE}"
			(at -0.939 -4.599 45)
			(layer "B.Fab")
			(hide yes)
			(effects
				(font
					(size 0.7 0.7)
					(thickness 0.15)
				)
				(justify right bottom mirror)
			)
		)
		(fp_text user "License: Apache-2.0"
			(at -0.939 -5.799 45)
			(layer "B.Fab")
			(hide yes)
			(effects
				(font
					(size 0.7 0.7)
					(thickness 0.15)
				)
				(justify right bottom mirror)
			)
		)
		(fp_text user "Author: Antmicro"
			(at -0.939 -3.399 45)
			(layer "B.Fab")
			(hide yes)
			(effects
				(font
					(size 0.7 0.7)
					(thickness 0.15)
				)
				(justify right bottom mirror)
			)
		)
		(pad "1" smd roundrect
			(at -0.48 0 45)
			(size 0.59 0.64)
			(layers "B.Cu" "B.Paste" "B.Mask")
			(roundrect_rratio 0.25)
			(net 1 "GND")
			(pintype "passive")
		)
		(pad "2" smd roundrect
			(at 0.48 0 45)
			(size 0.59 0.64)
			(layers "B.Cu" "B.Paste" "B.Mask")
			(roundrect_rratio 0.25)
			(net 15 "Net-(U6-CAP_VDD)")
			(pintype "passive")
		)
	)
	(footprint "antmicro-footprints:C_0402_1005Metric"
		(layer "B.Cu")
		(at 149.48 100.75 45)
		(descr "Capacitor SMD 0402")
		(tags "capacitor SMD 0402")
		(property "Reference" "C27"
			(at -3.570889 0.403051 45)
			(layer "B.SilkS")
			(effects
				(font
					(size 0.7 0.7)
					(thickness 0.15)
				)
				(justify right bottom mirror)
			)
		)
		(property "Value" "C_10n_0402"
			(at -0.676445 -2.119857 45)
			(layer "B.Fab")
			(effects
				(font
					(size 0.7 0.7)
					(thickness 0.15)
				)
				(justify right bottom mirror)
			)
		)
		(property "Footprint" "antmicro-footprints:C_0402_1005Metric"
			(at 0 0 45)
			(layer "F.Fab")
			(hide yes)
			(effects
				(font
					(size 1.27 1.27)
					(thickness 0.15)
				)
			)
		)
		(property "Datasheet" "https://www.murata.com/products/productdetail?partno=GRM155R71H103KA88%23"
			(at 0 0 45)
			(layer "F.Fab")
			(hide yes)
			(effects
				(font
					(size 1.27 1.27)
					(thickness 0.15)
				)
			)
		)
		(property "Author" "Antmicro"
			(at 115.022686 -76.189329 0)
			(layer "B.Fab")
			(hide yes)
			(effects
				(font
					(size 1 1)
					(thickness 0.15)
				)
				(justify mirror)
			)
		)
		(property "Dielectric" "X7R"
			(at 115.022686 -76.189329 0)
			(layer "B.Fab")
			(hide yes)
			(effects
				(font
					(size 1 1)
					(thickness 0.15)
				)
				(justify mirror)
			)
		)
		(property "License" "Apache-2.0"
			(at 115.022686 -76.189329 0)
			(layer "B.Fab")
			(hide yes)
			(effects
				(font
					(size 1 1)
					(thickness 0.15)
				)
				(justify mirror)
			)
		)
		(property "MPN" "GRM155R71H103KA88D"
			(at 115.022686 -76.189329 0)
			(layer "B.Fab")
			(hide yes)
			(effects
				(font
					(size 1 1)
					(thickness 0.15)
				)
				(justify mirror)
			)
		)
		(property "Manufacturer" "Murata"
			(at 115.022686 -76.189329 0)
			(layer "B.Fab")
			(hide yes)
			(effects
				(font
					(size 1 1)
					(thickness 0.15)
				)
				(justify mirror)
			)
		)
		(property "Val" "10n"
			(at 115.022686 -76.189329 0)
			(layer "B.Fab")
			(hide yes)
			(effects
				(font
					(size 1 1)
					(thickness 0.15)
				)
				(justify mirror)
			)
		)
		(property "Voltage" "50V"
			(at 115.022686 -76.189329 0)
			(layer "B.Fab")
			(hide yes)
			(effects
				(font
					(size 1 1)
					(thickness 0.15)
				)
				(justify mirror)
			)
		)
		(sheetname "Serializer")
		(sheetfile "serializer.kicad_sch")
		(attr smd)
		(fp_poly
			(pts
				(xy -0.925 0.47) (xy 0.925 0.47) (xy 0.925 -0.47) (xy -0.925 -0.47)
			)
			(stroke
				(width 0.05)
				(type default)
			)
			(fill none)
			(layer "B.CrtYd")
		)
		(fp_line
			(start -0.494 -0.248)
			(end 0.504 -0.248)
			(stroke
				(width 0.15)
				(type solid)
			)
			(layer "B.Fab")
		)
		(fp_line
			(start -0.494 0.25)
			(end -0.494 -0.248)
			(stroke
				(width 0.15)
				(type solid)
			)
			(layer "B.Fab")
		)
		(fp_line
			(start 0.504 -0.248)
			(end 0.504 0.25)
			(stroke
				(width 0.15)
				(type solid)
			)
			(layer "B.Fab")
		)
		(fp_line
			(start 0.504 0.25)
			(end -0.494 0.25)
			(stroke
				(width 0.15)
				(type solid)
			)
			(layer "B.Fab")
		)
		(fp_text user "${REFERENCE}"
			(at -0.939 -4.599 45)
			(layer "B.Fab")
			(hide yes)
			(effects
				(font
					(size 0.7 0.7)
					(thickness 0.15)
				)
				(justify right bottom mirror)
			)
		)
		(fp_text user "License: Apache-2.0"
			(at -0.939 -5.799 45)
			(layer "B.Fab")
			(hide yes)
			(effects
				(font
					(size 0.7 0.7)
					(thickness 0.15)
				)
				(justify right bottom mirror)
			)
		)
		(fp_text user "Author: Antmicro"
			(at -0.939 -3.399 45)
			(layer "B.Fab")
			(hide yes)
			(effects
				(font
					(size 0.7 0.7)
					(thickness 0.15)
				)
				(justify right bottom mirror)
			)
		)
		(pad "1" smd roundrect
			(at -0.48 0 45)
			(size 0.59 0.64)
			(layers "B.Cu" "B.Paste" "B.Mask")
			(roundrect_rratio 0.25)
			(net 1 "GND")
			(pintype "passive")
		)
		(pad "2" smd roundrect
			(at 0.48 0 45)
			(size 0.59 0.64)
			(layers "B.Cu" "B.Paste" "B.Mask")
			(roundrect_rratio 0.25)
			(net 11 "+1V8")
			(pintype "passive")
		)
	)
	(footprint "antmicro-footprints:C_0402_1005Metric"
		(layer "B.Cu")
		(at 148.790071 100.060072 45)
		(descr "Capacitor SMD 0402")
		(tags "capacitor SMD 0402")
		(property "Reference" "C23"
			(at -3.563817 0.438305 45)
			(layer "B.SilkS")
			(effects
				(font
					(size 0.7 0.7)
					(thickness 0.15)
				)
				(justify right bottom mirror)
			)
		)
		(property "Value" "C_10n_0402"
			(at -1.022927 -2.155213 45)
			(layer "B.Fab")
			(effects
				(font
					(size 0.7 0.7)
					(thickness 0.15)
				)
				(justify right bottom mirror)
			)
		)
		(property "Footprint" "antmicro-footprints:C_0402_1005Metric"
			(at 0 0 45)
			(layer "F.Fab")
			(hide yes)
			(effects
				(font
					(size 1.27 1.27)
					(thickness 0.15)
				)
			)
		)
		(property "Datasheet" "https://www.murata.com/products/productdetail?partno=GRM155R71H103KA88%23"
			(at 0 0 45)
			(layer "F.Fab")
			(hide yes)
			(effects
				(font
					(size 1.27 1.27)
					(thickness 0.15)
				)
			)
		)
		(property "Author" "Antmicro"
			(at 114.332759 -75.903552 0)
			(layer "B.Fab")
			(hide yes)
			(effects
				(font
					(size 1 1)
					(thickness 0.15)
				)
				(justify mirror)
			)
		)
		(property "Dielectric" "X7R"
			(at 114.332759 -75.903552 0)
			(layer "B.Fab")
			(hide yes)
			(effects
				(font
					(size 1 1)
					(thickness 0.15)
				)
				(justify mirror)
			)
		)
		(property "License" "Apache-2.0"
			(at 114.332759 -75.903552 0)
			(layer "B.Fab")
			(hide yes)
			(effects
				(font
					(size 1 1)
					(thickness 0.15)
				)
				(justify mirror)
			)
		)
		(property "MPN" "GRM155R71H103KA88D"
			(at 114.332759 -75.903552 0)
			(layer "B.Fab")
			(hide yes)
			(effects
				(font
					(size 1 1)
					(thickness 0.15)
				)
				(justify mirror)
			)
		)
		(property "Manufacturer" "Murata"
			(at 114.332759 -75.903552 0)
			(layer "B.Fab")
			(hide yes)
			(effects
				(font
					(size 1 1)
					(thickness 0.15)
				)
				(justify mirror)
			)
		)
		(property "Val" "10n"
			(at 114.332759 -75.903552 0)
			(layer "B.Fab")
			(hide yes)
			(effects
				(font
					(size 1 1)
					(thickness 0.15)
				)
				(justify mirror)
			)
		)
		(property "Voltage" "50V"
			(at 114.332759 -75.903552 0)
			(layer "B.Fab")
			(hide yes)
			(effects
				(font
					(size 1 1)
					(thickness 0.15)
				)
				(justify mirror)
			)
		)
		(sheetname "Serializer")
		(sheetfile "serializer.kicad_sch")
		(attr smd)
		(fp_poly
			(pts
				(xy -0.925 0.47) (xy 0.925 0.47) (xy 0.925 -0.47) (xy -0.925 -0.47)
			)
			(stroke
				(width 0.05)
				(type default)
			)
			(fill none)
			(layer "B.CrtYd")
		)
		(fp_line
			(start -0.494 -0.248)
			(end 0.504 -0.248)
			(stroke
				(width 0.15)
				(type solid)
			)
			(layer "B.Fab")
		)
		(fp_line
			(start -0.494 0.25)
			(end -0.494 -0.248)
			(stroke
				(width 0.15)
				(type solid)
			)
			(layer "B.Fab")
		)
		(fp_line
			(start 0.504 -0.248)
			(end 0.504 0.25)
			(stroke
				(width 0.15)
				(type solid)
			)
			(layer "B.Fab")
		)
		(fp_line
			(start 0.504 0.25)
			(end -0.494 0.25)
			(stroke
				(width 0.15)
				(type solid)
			)
			(layer "B.Fab")
		)
		(fp_text user "${REFERENCE}"
			(at -0.939 -4.599 45)
			(layer "B.Fab")
			(hide yes)
			(effects
				(font
					(size 0.7 0.7)
					(thickness 0.15)
				)
				(justify right bottom mirror)
			)
		)
		(fp_text user "Author: Antmicro"
			(at -0.939 -3.399 45)
			(layer "B.Fab")
			(hide yes)
			(effects
				(font
					(size 0.7 0.7)
					(thickness 0.15)
				)
				(justify right bottom mirror)
			)
		)
		(fp_text user "License: Apache-2.0"
			(at -0.939 -5.799 45)
			(layer "B.Fab")
			(hide yes)
			(effects
				(font
					(size 0.7 0.7)
					(thickness 0.15)
				)
				(justify right bottom mirror)
			)
		)
		(pad "1" smd roundrect
			(at -0.48 0 45)
			(size 0.59 0.64)
			(layers "B.Cu" "B.Paste" "B.Mask")
			(roundrect_rratio 0.25)
			(net 1 "GND")
			(pintype "passive")
		)
		(pad "2" smd roundrect
			(at 0.48 0 45)
			(size 0.59 0.64)
			(layers "B.Cu" "B.Paste" "B.Mask")
			(roundrect_rratio 0.25)
			(net 15 "Net-(U6-CAP_VDD)")
			(pintype "passive")
		)
	)
)
